(kicad_pcb
	(version 20260206)
	(generator "pcbnew")
	(generator_version "10.0")
	(general
		(thickness 1.6)
		(legacy_teardrops no)
	)
	(paper "A4")
	(title_block
		(title "03242023_DA0F0TMBIJ0_F0T_Motherboard_J_brd_V01_OCP.brd")
		(comment 1 "Grand Teton / footprints 2242-2247 of 6105")
	)
	(layers
		(0 "F.Cu" signal "TOP")
		(4 "In1.Cu" signal "GND")
		(6 "In2.Cu" signal "IN1")
		(8 "In3.Cu" signal "GND1")
		(10 "In4.Cu" signal "IN2")
		(12 "In5.Cu" signal "GND2")
		(14 "In6.Cu" signal "IN3")
		(16 "In7.Cu" signal "GND3")
		(18 "In8.Cu" signal "VCC")
		(20 "In9.Cu" signal "VCC1")
		(22 "In10.Cu" signal "GND4")
		(24 "In11.Cu" signal "IN4")
		(26 "In12.Cu" signal "GND5")
		(28 "In13.Cu" signal "IN5")
		(30 "In14.Cu" signal "GND6")
		(32 "In15.Cu" signal "IN6")
		(34 "In16.Cu" signal "GND7")
		(2 "B.Cu" signal "BOTTOM")
		(9 "F.Adhes" user "F.Adhesive")
		(11 "B.Adhes" user "B.Adhesive")
		(13 "F.Paste" user "Package Geometry/Pastemask Top")
		(15 "B.Paste" user "Package Geometry/Pastemask Bottom")
		(5 "F.SilkS" user "Ref Des/Silkscreen Top")
		(7 "B.SilkS" user "Ref Des/Silkscreen Bottom")
		(1 "F.Mask" user "Board Geometry/Soldermask Top")
		(3 "B.Mask" user "Board Geometry/Soldermask Bottom")
		(17 "Dwgs.User" user "User.Drawings")
		(19 "Cmts.User" user "User.Comments")
		(21 "Eco1.User" user "User.Eco1")
		(23 "Eco2.User" user "User.Eco2")
		(25 "Edge.Cuts" user "Board Geometry/Outline")
		(27 "Margin" user)
		(31 "F.CrtYd" user "Package Geometry/Place Bound Top")
		(29 "B.CrtYd" user "Package Geometry/Place Bound Bottom")
		(35 "F.Fab" user "Ref Des/Assembly Top")
		(33 "B.Fab" user "Ref Des/Assembly Bottom")
	)
	(footprint ""
		(layer "F.Cu")
		(at 62.48273 -40.031162)
		(property "Reference" "Q119"
			(at -0.89789 -2.121916 0)
			(unlocked yes)
			(layer "F.SilkS")
			(effects
				(font
					(size 0.7874 0.5842)
					(thickness 0.1524)
				)
				(justify left)
			)
		)
		(property "Value" ""
			(at 0 0 0)
			(layer "F.Fab")
			(effects
				(font
					(size 1.27 1.27)
				)
			)
		)
		(duplicate_pad_numbers_are_jumpers no)
		(fp_line
			(start -1.332738 -1.100074)
			(end -0.4826 -1.100074)
			(stroke
				(width 0.1524)
				(type default)
			)
			(layer "F.SilkS")
		)
		(fp_line
			(start -1.332738 1.100074)
			(end -1.332738 -1.100074)
			(stroke
				(width 0.1524)
				(type default)
			)
			(layer "F.SilkS")
		)
		(fp_line
			(start -0.4826 -1.100074)
			(end 0 -0.541274)
			(stroke
				(width 0.1524)
				(type default)
			)
			(layer "F.SilkS")
		)
		(fp_line
			(start 0 -0.541274)
			(end 0.4826 -1.100074)
			(stroke
				(width 0.1524)
				(type default)
			)
			(layer "F.SilkS")
		)
		(fp_line
			(start 0.4826 -1.100074)
			(end 1.332738 -1.100074)
			(stroke
				(width 0.1524)
				(type default)
			)
			(layer "F.SilkS")
		)
		(fp_line
			(start 1.332738 -1.100074)
			(end 1.332738 1.100074)
			(stroke
				(width 0.1524)
				(type default)
			)
			(layer "F.SilkS")
		)
		(fp_line
			(start 1.332738 1.100074)
			(end -1.332738 1.100074)
			(stroke
				(width 0.1524)
				(type default)
			)
			(layer "F.SilkS")
		)
		(fp_poly
			(pts
				(xy -2.2352 -1.001014) (xy -1.533144 -0.649986) (xy -2.2352 -0.298958)
			)
			(stroke
				(width 0)
				(type default)
			)
			(fill yes)
			(layer "F.SilkS")
		)
		(fp_line
			(start -0.674878 -1.100074)
			(end 0.674878 -1.100074)
			(stroke
				(width 0.1)
				(type default)
			)
			(layer "F.Fab")
		)
		(fp_line
			(start -0.674878 1.100074)
			(end -0.674878 -1.100074)
			(stroke
				(width 0.1)
				(type default)
			)
			(layer "F.Fab")
		)
		(fp_line
			(start 0.674878 -1.100074)
			(end 0.674878 1.100074)
			(stroke
				(width 0.1)
				(type default)
			)
			(layer "F.Fab")
		)
		(fp_line
			(start 0.674878 1.100074)
			(end -0.674878 1.100074)
			(stroke
				(width 0.1)
				(type default)
			)
			(layer "F.Fab")
		)
		(fp_poly
			(pts
				(xy -2.2352 -0.298958) (xy -2.2352 -1.001014) (xy -1.533144 -0.649986)
			)
			(stroke
				(width 0)
				(type default)
			)
			(fill yes)
			(layer "F.Fab")
		)
		(pad "1" smd rect
			(at -0.94996 -0.649986 90)
			(size 0.4318 0.508)
			(layers "F.Cu" "F.Mask" "F.Paste")
			(net "GND")
		)
		(pad "2" smd rect
			(at -0.94996 0 90)
			(size 0.4318 0.508)
			(layers "F.Cu" "F.Mask" "F.Paste")
			(net "P3V3_OCP_EN_2_R")
		)
		(pad "3" smd rect
			(at -0.94996 0.649986 90)
			(size 0.4318 0.508)
			(layers "F.Cu" "F.Mask" "F.Paste")
			(net "P3V3_OCP_UV_2_R1")
		)
		(pad "4" smd rect
			(at 0.94996 0.649986 90)
			(size 0.4318 0.508)
			(layers "F.Cu" "F.Mask" "F.Paste")
			(net "GND")
		)
		(pad "5" smd rect
			(at 0.94996 0 90)
			(size 0.4318 0.508)
			(layers "F.Cu" "F.Mask" "F.Paste")
			(net "P3V3_OCP_2_EN_G")
		)
		(pad "6" smd rect
			(at 0.94996 -0.649986 90)
			(size 0.4318 0.508)
			(layers "F.Cu" "F.Mask" "F.Paste")
			(net "P3V3_OCP_2_EN_G")
		)
	)
	(footprint ""
		(layer "F.Cu")
		(at 32.145732 -412.069534 180)
		(property "Reference" "R3474"
			(at 0 0 180)
			(layer "F.SilkS")
			(hide yes)
			(effects
				(font
					(size 1.27 1.27)
				)
			)
		)
		(property "Value" ""
			(at 0 0 180)
			(layer "F.Fab")
			(effects
				(font
					(size 1.27 1.27)
				)
			)
		)
		(duplicate_pad_numbers_are_jumpers no)
		(fp_line
			(start 0.7874 0.4064)
			(end -0.7874 0.4064)
			(stroke
				(width 0.1524)
				(type default)
			)
			(layer "F.SilkS")
		)
		(fp_line
			(start 0.7874 -0.4064)
			(end 0.7874 0.4064)
			(stroke
				(width 0.1524)
				(type default)
			)
			(layer "F.SilkS")
		)
		(fp_line
			(start -0.7874 0.4064)
			(end -0.7874 -0.4064)
			(stroke
				(width 0.1524)
				(type default)
			)
			(layer "F.SilkS")
		)
		(fp_line
			(start -0.7874 -0.4064)
			(end 0.7874 -0.4064)
			(stroke
				(width 0.1524)
				(type default)
			)
			(layer "F.SilkS")
		)
		(fp_line
			(start 0.67945 0.3048)
			(end 0.120396 0.3048)
			(stroke
				(width 0.1)
				(type default)
			)
			(layer "F.Fab")
		)
		(fp_line
			(start 0.67945 -0.3048)
			(end 0.67945 0.3048)
			(stroke
				(width 0.1)
				(type default)
			)
			(layer "F.Fab")
		)
		(fp_line
			(start 0.12065 -0.2794)
			(end 0.12065 -0.3048)
			(stroke
				(width 0.1)
				(type default)
			)
			(layer "F.Fab")
		)
		(fp_line
			(start 0.12065 -0.3048)
			(end 0.67945 -0.3048)
			(stroke
				(width 0.1)
				(type default)
			)
			(layer "F.Fab")
		)
		(fp_line
			(start 0.120396 0.3048)
			(end 0.120396 0.2794)
			(stroke
				(width 0.1)
				(type default)
			)
			(layer "F.Fab")
		)
		(fp_line
			(start 0.120396 0.2794)
			(end -0.12065 0.2794)
			(stroke
				(width 0.1)
				(type default)
			)
			(layer "F.Fab")
		)
		(fp_line
			(start -0.12065 0.3048)
			(end -0.67945 0.3048)
			(stroke
				(width 0.1)
				(type default)
			)
			(layer "F.Fab")
		)
		(fp_line
			(start -0.12065 0.2794)
			(end -0.12065 0.3048)
			(stroke
				(width 0.1)
				(type default)
			)
			(layer "F.Fab")
		)
		(fp_line
			(start -0.12065 -0.2794)
			(end 0.12065 -0.2794)
			(stroke
				(width 0.1)
				(type default)
			)
			(layer "F.Fab")
		)
		(fp_line
			(start -0.12065 -0.305054)
			(end -0.12065 -0.2794)
			(stroke
				(width 0.1)
				(type default)
			)
			(layer "F.Fab")
		)
		(fp_line
			(start -0.67945 0.3048)
			(end -0.67945 -0.305054)
			(stroke
				(width 0.1)
				(type default)
			)
			(layer "F.Fab")
		)
		(fp_line
			(start -0.67945 -0.305054)
			(end -0.12065 -0.305054)
			(stroke
				(width 0.1)
				(type default)
			)
			(layer "F.Fab")
		)
		(pad "1" smd circle
			(at -0.40005 0 180)
			(size 0 0)
			(layers "F.Cu" "F.Mask" "F.Paste")
			(net "P3V3_AUX")
		)
		(pad "2" smd circle
			(at 0.40005 0 180)
			(size 0 0)
			(layers "F.Cu" "F.Mask" "F.Paste")
			(net "GPU_PRSNT")
		)
	)
	(footprint ""
		(layer "F.Cu")
		(at 372.988332 -333.804514 -90)
		(property "Reference" "PC276_P0_4"
			(at 0 0 270)
			(layer "F.SilkS")
			(hide yes)
			(effects
				(font
					(size 1.27 1.27)
				)
			)
		)
		(property "Value" ""
			(at 0 0 270)
			(layer "F.Fab")
			(effects
				(font
					(size 1.27 1.27)
				)
			)
		)
		(duplicate_pad_numbers_are_jumpers no)
		(fp_line
			(start -0.7874 0.4064)
			(end -0.7874 -0.4064)
			(stroke
				(width 0.1524)
				(type default)
			)
			(layer "F.SilkS")
		)
		(fp_line
			(start 0.7874 0.4064)
			(end -0.7874 0.4064)
			(stroke
				(width 0.1524)
				(type default)
			)
			(layer "F.SilkS")
		)
		(fp_line
			(start -0.7874 -0.4064)
			(end 0.7874 -0.4064)
			(stroke
				(width 0.1524)
				(type default)
			)
			(layer "F.SilkS")
		)
		(fp_line
			(start 0.7874 -0.4064)
			(end 0.7874 0.4064)
			(stroke
				(width 0.1524)
				(type default)
			)
			(layer "F.SilkS")
		)
		(fp_line
			(start -0.67945 0.3048)
			(end -0.67945 -0.305054)
			(stroke
				(width 0.1)
				(type default)
			)
			(layer "F.Fab")
		)
		(fp_line
			(start -0.12065 0.3048)
			(end -0.67945 0.3048)
			(stroke
				(width 0.1)
				(type default)
			)
			(layer "F.Fab")
		)
		(fp_line
			(start 0.120396 0.3048)
			(end 0.120396 0.2794)
			(stroke
				(width 0.1)
				(type default)
			)
			(layer "F.Fab")
		)
		(fp_line
			(start 0.67945 0.3048)
			(end 0.120396 0.3048)
			(stroke
				(width 0.1)
				(type default)
			)
			(layer "F.Fab")
		)
		(fp_line
			(start -0.12065 0.2794)
			(end -0.12065 0.3048)
			(stroke
				(width 0.1)
				(type default)
			)
			(layer "F.Fab")
		)
		(fp_line
			(start 0.120396 0.2794)
			(end -0.12065 0.2794)
			(stroke
				(width 0.1)
				(type default)
			)
			(layer "F.Fab")
		)
		(fp_line
			(start -0.12065 -0.2794)
			(end 0.12065 -0.2794)
			(stroke
				(width 0.1)
				(type default)
			)
			(layer "F.Fab")
		)
		(fp_line
			(start 0.12065 -0.2794)
			(end 0.12065 -0.3048)
			(stroke
				(width 0.1)
				(type default)
			)
			(layer "F.Fab")
		)
		(fp_line
			(start 0.12065 -0.3048)
			(end 0.67945 -0.3048)
			(stroke
				(width 0.1)
				(type default)
			)
			(layer "F.Fab")
		)
		(fp_line
			(start 0.67945 -0.3048)
			(end 0.67945 0.3048)
			(stroke
				(width 0.1)
				(type default)
			)
			(layer "F.Fab")
		)
		(fp_line
			(start -0.67945 -0.305054)
			(end -0.12065 -0.305054)
			(stroke
				(width 0.1)
				(type default)
			)
			(layer "F.Fab")
		)
		(fp_line
			(start -0.12065 -0.305054)
			(end -0.12065 -0.2794)
			(stroke
				(width 0.1)
				(type default)
			)
			(layer "F.Fab")
		)
		(pad "1" smd circle
			(at -0.40005 0 270)
			(size 0 0)
			(layers "F.Cu" "F.Mask" "F.Paste")
			(net "SW_P12V_PVCCIN_CPU0_FLT")
		)
		(pad "2" smd circle
			(at 0.40005 0 270)
			(size 0 0)
			(layers "F.Cu" "F.Mask" "F.Paste")
			(net "GND")
		)
	)
	(footprint ""
		(layer "F.Cu")
		(at 292.273228 -413.07512 180)
		(property "Reference" "R4553"
			(at 0 0 180)
			(layer "F.SilkS")
			(hide yes)
			(effects
				(font
					(size 1.27 1.27)
				)
			)
		)
		(property "Value" ""
			(at 0 0 180)
			(layer "F.Fab")
			(effects
				(font
					(size 1.27 1.27)
				)
			)
		)
		(duplicate_pad_numbers_are_jumpers no)
		(fp_line
			(start 0.7874 0.4064)
			(end -0.7874 0.4064)
			(stroke
				(width 0.1524)
				(type default)
			)
			(layer "F.SilkS")
		)
		(fp_line
			(start 0.7874 -0.4064)
			(end 0.7874 0.4064)
			(stroke
				(width 0.1524)
				(type default)
			)
			(layer "F.SilkS")
		)
		(fp_line
			(start -0.7874 0.4064)
			(end -0.7874 -0.4064)
			(stroke
				(width 0.1524)
				(type default)
			)
			(layer "F.SilkS")
		)
		(fp_line
			(start -0.7874 -0.4064)
			(end 0.7874 -0.4064)
			(stroke
				(width 0.1524)
				(type default)
			)
			(layer "F.SilkS")
		)
		(fp_line
			(start 0.67945 0.3048)
			(end 0.120396 0.3048)
			(stroke
				(width 0.1)
				(type default)
			)
			(layer "F.Fab")
		)
		(fp_line
			(start 0.67945 -0.3048)
			(end 0.67945 0.3048)
			(stroke
				(width 0.1)
				(type default)
			)
			(layer "F.Fab")
		)
		(fp_line
			(start 0.12065 -0.2794)
			(end 0.12065 -0.3048)
			(stroke
				(width 0.1)
				(type default)
			)
			(layer "F.Fab")
		)
		(fp_line
			(start 0.12065 -0.3048)
			(end 0.67945 -0.3048)
			(stroke
				(width 0.1)
				(type default)
			)
			(layer "F.Fab")
		)
		(fp_line
			(start 0.120396 0.3048)
			(end 0.120396 0.2794)
			(stroke
				(width 0.1)
				(type default)
			)
			(layer "F.Fab")
		)
		(fp_line
			(start 0.120396 0.2794)
			(end -0.12065 0.2794)
			(stroke
				(width 0.1)
				(type default)
			)
			(layer "F.Fab")
		)
		(fp_line
			(start -0.12065 0.3048)
			(end -0.67945 0.3048)
			(stroke
				(width 0.1)
				(type default)
			)
			(layer "F.Fab")
		)
		(fp_line
			(start -0.12065 0.2794)
			(end -0.12065 0.3048)
			(stroke
				(width 0.1)
				(type default)
			)
			(layer "F.Fab")
		)
		(fp_line
			(start -0.12065 -0.2794)
			(end 0.12065 -0.2794)
			(stroke
				(width 0.1)
				(type default)
			)
			(layer "F.Fab")
		)
		(fp_line
			(start -0.12065 -0.305054)
			(end -0.12065 -0.2794)
			(stroke
				(width 0.1)
				(type default)
			)
			(layer "F.Fab")
		)
		(fp_line
			(start -0.67945 0.3048)
			(end -0.67945 -0.305054)
			(stroke
				(width 0.1)
				(type default)
			)
			(layer "F.Fab")
		)
		(fp_line
			(start -0.67945 -0.305054)
			(end -0.12065 -0.305054)
			(stroke
				(width 0.1)
				(type default)
			)
			(layer "F.Fab")
		)
		(pad "1" smd circle
			(at -0.40005 0 180)
			(size 0 0)
			(layers "F.Cu" "F.Mask" "F.Paste")
			(net "P3V3_AUX")
		)
		(pad "2" smd circle
			(at 0.40005 0 180)
			(size 0 0)
			(layers "F.Cu" "F.Mask" "F.Paste")
			(net "HPDB_HSC_PWRGD_N")
		)
	)
	(footprint ""
		(layer "F.Cu")
		(at 169.436288 -417.237418)
		(property "Reference" "R3434"
			(at 0 0 0)
			(layer "F.SilkS")
			(hide yes)
			(effects
				(font
					(size 1.27 1.27)
				)
			)
		)
		(property "Value" ""
			(at 0 0 0)
			(layer "F.Fab")
			(effects
				(font
					(size 1.27 1.27)
				)
			)
		)
		(duplicate_pad_numbers_are_jumpers no)
		(fp_line
			(start -0.7874 -0.4064)
			(end 0.7874 -0.4064)
			(stroke
				(width 0.1524)
				(type default)
			)
			(layer "F.SilkS")
		)
		(fp_line
			(start -0.7874 0.4064)
			(end -0.7874 -0.4064)
			(stroke
				(width 0.1524)
				(type default)
			)
			(layer "F.SilkS")
		)
		(fp_line
			(start 0.7874 -0.4064)
			(end 0.7874 0.4064)
			(stroke
				(width 0.1524)
				(type default)
			)
			(layer "F.SilkS")
		)
		(fp_line
			(start 0.7874 0.4064)
			(end -0.7874 0.4064)
			(stroke
				(width 0.1524)
				(type default)
			)
			(layer "F.SilkS")
		)
		(fp_line
			(start -0.67945 -0.305054)
			(end -0.12065 -0.305054)
			(stroke
				(width 0.1)
				(type default)
			)
			(layer "F.Fab")
		)
		(fp_line
			(start -0.67945 0.3048)
			(end -0.67945 -0.305054)
			(stroke
				(width 0.1)
				(type default)
			)
			(layer "F.Fab")
		)
		(fp_line
			(start -0.12065 -0.305054)
			(end -0.12065 -0.2794)
			(stroke
				(width 0.1)
				(type default)
			)
			(layer "F.Fab")
		)
		(fp_line
			(start -0.12065 -0.2794)
			(end 0.12065 -0.2794)
			(stroke
				(width 0.1)
				(type default)
			)
			(layer "F.Fab")
		)
		(fp_line
			(start -0.12065 0.2794)
			(end -0.12065 0.3048)
			(stroke
				(width 0.1)
				(type default)
			)
			(layer "F.Fab")
		)
		(fp_line
			(start -0.12065 0.3048)
			(end -0.67945 0.3048)
			(stroke
				(width 0.1)
				(type default)
			)
			(layer "F.Fab")
		)
		(fp_line
			(start 0.120396 0.2794)
			(end -0.12065 0.2794)
			(stroke
				(width 0.1)
				(type default)
			)
			(layer "F.Fab")
		)
		(fp_line
			(start 0.120396 0.3048)
			(end 0.120396 0.2794)
			(stroke
				(width 0.1)
				(type default)
			)
			(layer "F.Fab")
		)
		(fp_line
			(start 0.12065 -0.3048)
			(end 0.67945 -0.3048)
			(stroke
				(width 0.1)
				(type default)
			)
			(layer "F.Fab")
		)
		(fp_line
			(start 0.12065 -0.2794)
			(end 0.12065 -0.3048)
			(stroke
				(width 0.1)
				(type default)
			)
			(layer "F.Fab")
		)
		(fp_line
			(start 0.67945 -0.3048)
			(end 0.67945 0.3048)
			(stroke
				(width 0.1)
				(type default)
			)
			(layer "F.Fab")
		)
		(fp_line
			(start 0.67945 0.3048)
			(end 0.120396 0.3048)
			(stroke
				(width 0.1)
				(type default)
			)
			(layer "F.Fab")
		)
		(pad "1" smd circle
			(at -0.40005 0)
			(size 0 0)
			(layers "F.Cu" "F.Mask" "F.Paste")
			(net "P3V3_AUX")
		)
		(pad "2" smd circle
			(at 0.40005 0)
			(size 0 0)
			(layers "F.Cu" "F.Mask" "F.Paste")
			(net "GPU_HMC_PRSNT")
		)
	)
	(footprint ""
		(layer "F.Cu")
		(at 329.795378 -27.042618 -90)
		(property "Reference" "R1872"
			(at 0 0 270)
			(layer "F.SilkS")
			(hide yes)
			(effects
				(font
					(size 1.27 1.27)
				)
			)
		)
		(property "Value" ""
			(at 0 0 270)
			(layer "F.Fab")
			(effects
				(font
					(size 1.27 1.27)
				)
			)
		)
		(duplicate_pad_numbers_are_jumpers no)
		(fp_line
			(start -0.7874 0.4064)
			(end -0.7874 -0.4064)
			(stroke
				(width 0.1524)
				(type default)
			)
			(layer "F.SilkS")
		)
		(fp_line
			(start 0.7874 0.4064)
			(end -0.7874 0.4064)
			(stroke
				(width 0.1524)
				(type default)
			)
			(layer "F.SilkS")
		)
		(fp_line
			(start -0.7874 -0.4064)
			(end 0.7874 -0.4064)
			(stroke
				(width 0.1524)
				(type default)
			)
			(layer "F.SilkS")
		)
		(fp_line
			(start 0.7874 -0.4064)
			(end 0.7874 0.4064)
			(stroke
				(width 0.1524)
				(type default)
			)
			(layer "F.SilkS")
		)
		(fp_line
			(start -0.67945 0.3048)
			(end -0.67945 -0.305054)
			(stroke
				(width 0.1)
				(type default)
			)
			(layer "F.Fab")
		)
		(fp_line
			(start -0.12065 0.3048)
			(end -0.67945 0.3048)
			(stroke
				(width 0.1)
				(type default)
			)
			(layer "F.Fab")
		)
		(fp_line
			(start 0.120396 0.3048)
			(end 0.120396 0.2794)
			(stroke
				(width 0.1)
				(type default)
			)
			(layer "F.Fab")
		)
		(fp_line
			(start 0.67945 0.3048)
			(end 0.120396 0.3048)
			(stroke
				(width 0.1)
				(type default)
			)
			(layer "F.Fab")
		)
		(fp_line
			(start -0.12065 0.2794)
			(end -0.12065 0.3048)
			(stroke
				(width 0.1)
				(type default)
			)
			(layer "F.Fab")
		)
		(fp_line
			(start 0.120396 0.2794)
			(end -0.12065 0.2794)
			(stroke
				(width 0.1)
				(type default)
			)
			(layer "F.Fab")
		)
		(fp_line
			(start -0.12065 -0.2794)
			(end 0.12065 -0.2794)
			(stroke
				(width 0.1)
				(type default)
			)
			(layer "F.Fab")
		)
		(fp_line
			(start 0.12065 -0.2794)
			(end 0.12065 -0.3048)
			(stroke
				(width 0.1)
				(type default)
			)
			(layer "F.Fab")
		)
		(fp_line
			(start 0.12065 -0.3048)
			(end 0.67945 -0.3048)
			(stroke
				(width 0.1)
				(type default)
			)
			(layer "F.Fab")
		)
		(fp_line
			(start 0.67945 -0.3048)
			(end 0.67945 0.3048)
			(stroke
				(width 0.1)
				(type default)
			)
			(layer "F.Fab")
		)
		(fp_line
			(start -0.67945 -0.305054)
			(end -0.12065 -0.305054)
			(stroke
				(width 0.1)
				(type default)
			)
			(layer "F.Fab")
		)
		(fp_line
			(start -0.12065 -0.305054)
			(end -0.12065 -0.2794)
			(stroke
				(width 0.1)
				(type default)
			)
			(layer "F.Fab")
		)
		(pad "1" smd circle
			(at -0.40005 0 270)
			(size 0 0)
			(layers "F.Cu" "F.Mask" "F.Paste")
			(net "CLK_24M_66M_LPC0_ESPI")
		)
		(pad "2" smd circle
			(at 0.40005 0 270)
			(size 0 0)
			(layers "F.Cu" "F.Mask" "F.Paste")
			(net "ESPI_HOST_LPC_BMC_CLK")
		)
	)
)
